(kicad_pcb
	(version 20241229)
	(generator "pcbnew")
	(generator_version "9.0")
	(general
		(thickness 1.711)
		(legacy_teardrops no)
	)
	(paper "A4")
	(title_block
		(title "Antmicro Baseboard for Jetson AGX Thor")
		(date "2026-02-18")
		(rev "1.1.0")
		(company "Antmicro Ltd")
		(comment 1 "www.antmicro.com")
		(comment 9 "footprints 500-503 of 1170")
	)
	(layers
		(0 "F.Cu" signal)
		(4 "In1.Cu" signal)
		(6 "In2.Cu" signal)
		(8 "In3.Cu" signal)
		(10 "In4.Cu" jumper)
		(12 "In5.Cu" signal)
		(14 "In6.Cu" signal)
		(16 "In7.Cu" signal)
		(18 "In8.Cu" signal)
		(2 "B.Cu" signal)
		(9 "F.Adhes" user "F.Adhesive")
		(11 "B.Adhes" user "B.Adhesive")
		(13 "F.Paste" user)
		(15 "B.Paste" user)
		(5 "F.SilkS" user "F.Silkscreen")
		(7 "B.SilkS" user "B.Silkscreen")
		(1 "F.Mask" user)
		(3 "B.Mask" user)
		(17 "Dwgs.User" user "User.Drawings")
		(19 "Cmts.User" user "User.Comments")
		(21 "Eco1.User" user "User.Eco1")
		(23 "Eco2.User" user "User.Eco2")
		(25 "Edge.Cuts" user)
		(27 "Margin" user)
		(31 "F.CrtYd" user "F.Courtyard")
		(29 "B.CrtYd" user "B.Courtyard")
		(35 "F.Fab" user)
		(33 "B.Fab" user)
	)
	(footprint "antmicro-footprints:R_0402_1005Metric"
		(layer "F.Cu")
		(at 215.8 120.1 -90)
		(descr "Resistor SMD 0402")
		(tags "resistor SMD 0402")
		(property "Reference" "R78"
			(at -3 0.4 90)
			(layer "F.SilkS")
			(effects
				(font
					(size 0.7 0.7)
					(thickness 0.15)
				)
				(justify right top)
			)
		)
		(property "Value" "R_200k_0402"
			(at -1.011843 1.772046 90)
			(layer "F.Fab")
			(effects
				(font
					(size 0.7 0.7)
					(thickness 0.15)
				)
				(justify right top)
			)
		)
		(property "Datasheet" "https://www.bourns.com/docs/product-datasheets/cr.pdf"
			(at 0 0 90)
			(layer "F.Fab")
			(hide yes)
			(effects
				(font
					(size 1.27 1.27)
					(thickness 0.15)
				)
			)
		)
		(property "Description" "SMD Chip Resistor, 200 kohm, ± 1%, 62.5 mW, 0402 [1005 Metric], Thick Film, General Purpose"
			(at 0 0 90)
			(layer "F.Fab")
			(hide yes)
			(effects
				(font
					(size 1.27 1.27)
					(thickness 0.15)
				)
			)
		)
		(property "MPN" "CR0402-FX-2003GLF"
			(at 0 0 270)
			(unlocked yes)
			(layer "F.Fab")
			(hide yes)
			(effects
				(font
					(size 1 1)
					(thickness 0.15)
				)
			)
		)
		(property "Manufacturer" "Bourns"
			(at 0 0 270)
			(unlocked yes)
			(layer "F.Fab")
			(hide yes)
			(effects
				(font
					(size 1 1)
					(thickness 0.15)
				)
			)
		)
		(property "License" "Apache-2.0"
			(at 0 0 270)
			(unlocked yes)
			(layer "F.Fab")
			(hide yes)
			(effects
				(font
					(size 1 1)
					(thickness 0.15)
				)
			)
		)
		(property "Author" "Antmicro"
			(at 0 0 270)
			(unlocked yes)
			(layer "F.Fab")
			(hide yes)
			(effects
				(font
					(size 1 1)
					(thickness 0.15)
				)
			)
		)
		(property "Val" "200k"
			(at 0 0 270)
			(unlocked yes)
			(layer "F.Fab")
			(hide yes)
			(effects
				(font
					(size 1 1)
					(thickness 0.15)
				)
			)
		)
		(property "Tolerance" "1%"
			(at 0 0 270)
			(unlocked yes)
			(layer "F.Fab")
			(hide yes)
			(effects
				(font
					(size 1 1)
					(thickness 0.15)
				)
			)
		)
		(sheetname "/USB Hub/")
		(sheetfile "usb_hub.kicad_sch")
		(attr smd exclude_from_pos_files exclude_from_bom dnp)
		(fp_poly
			(pts
				(xy -0.925 -0.47) (xy 0.925 -0.47) (xy 0.925 0.47) (xy -0.925 0.47)
			)
			(stroke
				(width 0.05)
				(type default)
			)
			(fill no)
			(layer "F.CrtYd")
		)
		(fp_poly
			(pts
				(xy -0.5 -0.25) (xy 0.5 -0.25) (xy 0.5 0.25) (xy -0.5 0.25)
			)
			(stroke
				(width 0.15)
				(type solid)
			)
			(fill no)
			(layer "F.Fab")
		)
		(fp_text user "License: Apache-2.0"
			(at -0.949999 5.169 90)
			(layer "F.Fab")
			(effects
				(font
					(size 0.7 0.7)
					(thickness 0.15)
				)
				(justify right top)
			)
		)
		(fp_text user "${REFERENCE}"
			(at -0.95 3.168 90)
			(layer "F.Fab")
			(effects
				(font
					(size 0.7 0.7)
					(thickness 0.15)
				)
				(justify right top)
			)
		)
		(fp_text user "Author: Antmicro"
			(at -0.95 4.169 90)
			(layer "F.Fab")
			(effects
				(font
					(size 0.7 0.7)
					(thickness 0.15)
				)
				(justify right top)
			)
		)
		(pad "1" smd roundrect
			(at -0.48 0 270)
			(size 0.59 0.64)
			(layers "F.Cu" "F.Mask" "F.Paste")
			(roundrect_rratio 0.25)
			(net 1 "GND")
			(pintype "passive")
		)
		(pad "2" smd roundrect
			(at 0.48 0 270)
			(size 0.59 0.64)
			(layers "F.Cu" "F.Mask" "F.Paste")
			(roundrect_rratio 0.25)
			(net 913 "/USB Hub/CFG_STRAP1")
			(pintype "passive")
		)
	)
	(footprint "antmicro-footprints:C_0402_1005Metric"
		(layer "F.Cu")
		(at 213.912407 98.212991 90)
		(descr "Capacitor SMD 0402")
		(tags "capacitor SMD 0402")
		(property "Reference" "C232"
			(at -1.787009 -2.612407 90)
			(layer "F.SilkS")
			(effects
				(font
					(size 0.7 0.7)
					(thickness 0.15)
				)
				(justify left bottom)
			)
		)
		(property "Value" "C_100n_0402"
			(at -1.022927 2.155213 90)
			(layer "F.Fab")
			(effects
				(font
					(size 0.7 0.7)
					(thickness 0.15)
				)
				(justify left bottom)
			)
		)
		(property "Datasheet" "https://www.murata.com/products/productdetail?partno=GRM155R61H104KE14%23"
			(at 0 0 90)
			(layer "F.Fab")
			(hide yes)
			(effects
				(font
					(size 1.27 1.27)
					(thickness 0.15)
				)
			)
		)
		(property "Description" "SMD Multilayer Ceramic Capacitor, 0.1 µF, 50 V, 0402 [1005 Metric], ± 10%, X5R, GRM Series"
			(at 0 0 90)
			(layer "F.Fab")
			(hide yes)
			(effects
				(font
					(size 1.27 1.27)
					(thickness 0.15)
				)
			)
		)
		(property "Manufacturer" "Murata"
			(at 0 0 90)
			(unlocked yes)
			(layer "F.Fab")
			(hide yes)
			(effects
				(font
					(size 1 1)
					(thickness 0.15)
				)
			)
		)
		(property "MPN" "GRM155R61H104KE14D"
			(at 0 0 90)
			(unlocked yes)
			(layer "F.Fab")
			(hide yes)
			(effects
				(font
					(size 1 1)
					(thickness 0.15)
				)
			)
		)
		(property "Val" "100n"
			(at 0 0 90)
			(unlocked yes)
			(layer "F.Fab")
			(hide yes)
			(effects
				(font
					(size 1 1)
					(thickness 0.15)
				)
			)
		)
		(property "License" "Apache-2.0"
			(at 0 0 90)
			(unlocked yes)
			(layer "F.Fab")
			(hide yes)
			(effects
				(font
					(size 1 1)
					(thickness 0.15)
				)
			)
		)
		(property "Author" "Antmicro"
			(at 0 0 90)
			(unlocked yes)
			(layer "F.Fab")
			(hide yes)
			(effects
				(font
					(size 1 1)
					(thickness 0.15)
				)
			)
		)
		(property "Voltage" "50V"
			(at 0 0 90)
			(unlocked yes)
			(layer "F.Fab")
			(hide yes)
			(effects
				(font
					(size 1 1)
					(thickness 0.15)
				)
			)
		)
		(property "Dielectric" "X5R"
			(at 0 0 90)
			(unlocked yes)
			(layer "F.Fab")
			(hide yes)
			(effects
				(font
					(size 1 1)
					(thickness 0.15)
				)
			)
		)
		(sheetname "/Recovery USB/")
		(sheetfile "recovery_usb.kicad_sch")
		(attr smd)
		(fp_poly
			(pts
				(xy -0.925 -0.47) (xy 0.925 -0.47) (xy 0.925 0.47) (xy -0.925 0.47)
			)
			(stroke
				(width 0.05)
				(type default)
			)
			(fill no)
			(layer "F.CrtYd")
		)
		(fp_line
			(start 0.504 -0.25)
			(end 0.504 0.248)
			(stroke
				(width 0.15)
				(type solid)
			)
			(layer "F.Fab")
		)
		(fp_line
			(start -0.494 -0.25)
			(end 0.504 -0.25)
			(stroke
				(width 0.15)
				(type solid)
			)
			(layer "F.Fab")
		)
		(fp_line
			(start 0.504 0.248)
			(end -0.494 0.248)
			(stroke
				(width 0.15)
				(type solid)
			)
			(layer "F.Fab")
		)
		(fp_line
			(start -0.494 0.248)
			(end -0.494 -0.25)
			(stroke
				(width 0.15)
				(type solid)
			)
			(layer "F.Fab")
		)
		(fp_text user "License: Apache-2.0"
			(at -0.939 5.799 90)
			(layer "F.Fab")
			(effects
				(font
					(size 0.7 0.7)
					(thickness 0.15)
				)
				(justify left bottom)
			)
		)
		(fp_text user "${REFERENCE}"
			(at -0.939 4.599 90)
			(layer "F.Fab")
			(effects
				(font
					(size 0.7 0.7)
					(thickness 0.15)
				)
				(justify left bottom)
			)
		)
		(fp_text user "Author: Antmicro"
			(at -0.939 3.399 90)
			(layer "F.Fab")
			(effects
				(font
					(size 0.7 0.7)
					(thickness 0.15)
				)
				(justify left bottom)
			)
		)
		(pad "1" smd roundrect
			(at -0.48 0 90)
			(size 0.59 0.64)
			(layers "F.Cu" "F.Mask" "F.Paste")
			(roundrect_rratio 0.25)
			(net 5 "+5V")
			(pintype "passive")
		)
		(pad "2" smd roundrect
			(at 0.48 0 90)
			(size 0.59 0.64)
			(layers "F.Cu" "F.Mask" "F.Paste")
			(roundrect_rratio 0.25)
			(net 1 "GND")
			(pintype "passive")
		)
	)
	(footprint "antmicro-footprints:C_0402_1005Metric"
		(layer "F.Cu")
		(at 177.94 142.88 -90)
		(descr "Capacitor SMD 0402")
		(tags "capacitor SMD 0402")
		(property "Reference" "C51"
			(at -2.93 0.47 90)
			(layer "F.SilkS")
			(effects
				(font
					(size 0.7 0.7)
					(thickness 0.15)
				)
				(justify right top)
			)
		)
		(property "Value" "C_100n_0402"
			(at -1.022927 2.155213 90)
			(layer "F.Fab")
			(effects
				(font
					(size 0.7 0.7)
					(thickness 0.15)
				)
				(justify right top)
			)
		)
		(property "Datasheet" "https://www.murata.com/products/productdetail?partno=GRM155R61H104KE14%23"
			(at 0 0 90)
			(layer "F.Fab")
			(hide yes)
			(effects
				(font
					(size 1.27 1.27)
					(thickness 0.15)
				)
			)
		)
		(property "Description" "SMD Multilayer Ceramic Capacitor, 0.1 µF, 50 V, 0402 [1005 Metric], ± 10%, X5R, GRM Series"
			(at 0 0 90)
			(layer "F.Fab")
			(hide yes)
			(effects
				(font
					(size 1.27 1.27)
					(thickness 0.15)
				)
			)
		)
		(property "Manufacturer" "Murata"
			(at 0 0 270)
			(unlocked yes)
			(layer "F.Fab")
			(hide yes)
			(effects
				(font
					(size 1 1)
					(thickness 0.15)
				)
			)
		)
		(property "MPN" "GRM155R61H104KE14D"
			(at 0 0 270)
			(unlocked yes)
			(layer "F.Fab")
			(hide yes)
			(effects
				(font
					(size 1 1)
					(thickness 0.15)
				)
			)
		)
		(property "Val" "100n"
			(at 0 0 270)
			(unlocked yes)
			(layer "F.Fab")
			(hide yes)
			(effects
				(font
					(size 1 1)
					(thickness 0.15)
				)
			)
		)
		(property "License" "Apache-2.0"
			(at 0 0 270)
			(unlocked yes)
			(layer "F.Fab")
			(hide yes)
			(effects
				(font
					(size 1 1)
					(thickness 0.15)
				)
			)
		)
		(property "Author" "Antmicro"
			(at 0 0 270)
			(unlocked yes)
			(layer "F.Fab")
			(hide yes)
			(effects
				(font
					(size 1 1)
					(thickness 0.15)
				)
			)
		)
		(property "Voltage" "50V"
			(at 0 0 270)
			(unlocked yes)
			(layer "F.Fab")
			(hide yes)
			(effects
				(font
					(size 1 1)
					(thickness 0.15)
				)
			)
		)
		(property "Dielectric" "X5R"
			(at 0 0 270)
			(unlocked yes)
			(layer "F.Fab")
			(hide yes)
			(effects
				(font
					(size 1 1)
					(thickness 0.15)
				)
			)
		)
		(sheetname "/DCDC/")
		(sheetfile "dcdc.kicad_sch")
		(attr smd)
		(fp_rect
			(start -0.925 -0.47)
			(end 0.925 0.47)
			(stroke
				(width 0.05)
				(type default)
			)
			(fill no)
			(layer "F.CrtYd")
		)
		(fp_line
			(start -0.494 0.248)
			(end -0.494 -0.25)
			(stroke
				(width 0.15)
				(type solid)
			)
			(layer "F.Fab")
		)
		(fp_line
			(start 0.504 0.248)
			(end -0.494 0.248)
			(stroke
				(width 0.15)
				(type solid)
			)
			(layer "F.Fab")
		)
		(fp_line
			(start -0.494 -0.25)
			(end 0.504 -0.25)
			(stroke
				(width 0.15)
				(type solid)
			)
			(layer "F.Fab")
		)
		(fp_line
			(start 0.504 -0.25)
			(end 0.504 0.248)
			(stroke
				(width 0.15)
				(type solid)
			)
			(layer "F.Fab")
		)
		(fp_text user "License: Apache-2.0"
			(at -0.939 5.799 90)
			(layer "F.Fab")
			(effects
				(font
					(size 0.7 0.7)
					(thickness 0.15)
				)
				(justify right top)
			)
		)
		(fp_text user "Author: Antmicro"
			(at -0.939 3.399 90)
			(layer "F.Fab")
			(effects
				(font
					(size 0.7 0.7)
					(thickness 0.15)
				)
				(justify right top)
			)
		)
		(fp_text user "${REFERENCE}"
			(at -0.939 4.599 90)
			(layer "F.Fab")
			(effects
				(font
					(size 0.7 0.7)
					(thickness 0.15)
				)
				(justify right top)
			)
		)
		(pad "1" smd roundrect
			(at -0.48 0 270)
			(size 0.59 0.64)
			(layers "F.Cu" "F.Mask" "F.Paste")
			(roundrect_rratio 0.25)
			(net 13 "VCC")
			(pintype "passive")
		)
		(pad "2" smd roundrect
			(at 0.48 0 270)
			(size 0.59 0.64)
			(layers "F.Cu" "F.Mask" "F.Paste")
			(roundrect_rratio 0.25)
			(net 1 "GND")
			(pintype "passive")
		)
	)
	(footprint "antmicro-footprints:TSOT23-6"
		(layer "F.Cu")
		(at 66.75 89 90)
		(property "Reference" "U44"
			(at -0.33 2.6 270)
			(layer "F.SilkS")
			(effects
				(font
					(size 0.7 0.7)
					(thickness 0.15)
				)
				(justify left bottom)
			)
		)
		(property "Value" "AP22615A_TSOT26"
			(at 0 2.6 90)
			(layer "F.Fab")
			(effects
				(font
					(size 0.7 0.7)
					(thickness 0.15)
				)
				(justify left bottom)
			)
		)
		(property "Datasheet" "https://www.mouser.com/datasheet/2/115/DIOD_S_A0008958405_1-2543193.pdf"
			(at 0 0 90)
			(layer "F.Fab")
			(hide yes)
			(effects
				(font
					(size 1.27 1.27)
					(thickness 0.15)
				)
			)
		)
		(property "Description" "Power Load Distribution Switch, High Side, Active High, 1 Output, 5.5 V, 3.6 A, 0.04 ohm, TSOT-26-6"
			(at 0 0 90)
			(layer "F.Fab")
			(hide yes)
			(effects
				(font
					(size 1.27 1.27)
					(thickness 0.15)
				)
			)
		)
		(property "MPN" "AP22615AWU-7"
			(at 0 0 90)
			(unlocked yes)
			(layer "F.Fab")
			(hide yes)
			(effects
				(font
					(size 1 1)
					(thickness 0.15)
				)
			)
		)
		(property "Manufacturer" "Diodes Incorporated"
			(at 0 0 90)
			(unlocked yes)
			(layer "F.Fab")
			(hide yes)
			(effects
				(font
					(size 1 1)
					(thickness 0.15)
				)
			)
		)
		(property "Author" "Antmicro"
			(at 0 0 90)
			(unlocked yes)
			(layer "F.Fab")
			(hide yes)
			(effects
				(font
					(size 1 1)
					(thickness 0.15)
				)
			)
		)
		(property "License" "Apache-2.0"
			(at 0 0 90)
			(unlocked yes)
			(layer "F.Fab")
			(hide yes)
			(effects
				(font
					(size 1 1)
					(thickness 0.15)
				)
			)
		)
		(sheetname "/CSI/")
		(sheetfile "csi.kicad_sch")
		(attr smd)
		(fp_line
			(start -1 -1.5)
			(end -1 -1.375)
			(stroke
				(width 0.15)
				(type solid)
			)
			(layer "F.SilkS")
		)
		(fp_line
			(start 1 -1.497)
			(end -1 -1.5)
			(stroke
				(width 0.15)
				(type solid)
			)
			(layer "F.SilkS")
		)
		(fp_line
			(start 1 -1.497)
			(end 1 -1.375)
			(stroke
				(width 0.15)
				(type solid)
			)
			(layer "F.SilkS")
		)
		(fp_line
			(start 1 1.55)
			(end 1 1.4)
			(stroke
				(width 0.15)
				(type solid)
			)
			(layer "F.SilkS")
		)
		(fp_line
			(start 1 1.55)
			(end -1 1.55)
			(stroke
				(width 0.15)
				(type solid)
			)
			(layer "F.SilkS")
		)
		(fp_line
			(start -1 1.55)
			(end -1 1.4)
			(stroke
				(width 0.15)
				(type solid)
			)
			(layer "F.SilkS")
		)
		(fp_circle
			(center -1.44 -1.5)
			(end -1.39 -1.5)
			(stroke
				(width 0.15)
				(type solid)
			)
			(fill yes)
			(layer "F.SilkS")
		)
		(fp_rect
			(start 1.93 -1.7)
			(end -1.93 1.7)
			(stroke
				(width 0.05)
				(type solid)
			)
			(fill no)
			(layer "F.CrtYd")
		)
		(fp_line
			(start -0.45 -1.521)
			(end -0.876 -1.096)
			(stroke
				(width 0.15)
				(type solid)
			)
			(layer "F.Fab")
		)
		(fp_rect
			(start 0.875 1.528)
			(end -0.875 -1.525)
			(stroke
				(width 0.15)
				(type solid)
			)
			(fill no)
			(layer "F.Fab")
		)
		(fp_text user "${REFERENCE}"
			(at -1.93 3.8 90)
			(layer "F.Fab")
			(effects
				(font
					(size 0.7 0.7)
					(thickness 0.15)
				)
				(justify left bottom)
			)
		)
		(fp_text user "Author: Antmicro"
			(at -1.93 5 90)
			(layer "F.Fab")
			(effects
				(font
					(size 0.7 0.7)
					(thickness 0.15)
				)
				(justify left bottom)
			)
		)
		(fp_text user "License: Apache-2.0"
			(at -1.93 6.199 90)
			(layer "F.Fab")
			(effects
				(font
					(size 0.7 0.7)
					(thickness 0.15)
				)
				(justify left bottom)
			)
		)
		(pad "1" smd rect
			(at -1.301 -0.947)
			(size 0.7 1.2)
			(layers "F.Cu" "F.Mask" "F.Paste")
			(net 7 "/CSI/CSIA_5V")
			(pinfunction "OUT")
			(pintype "power_out")
		)
		(pad "2" smd rect
			(at -1.301 0.004)
			(size 0.7 1.2)
			(layers "F.Cu" "F.Mask" "F.Paste")
			(net 1 "GND")
			(pinfunction "GND")
			(pintype "power_in")
		)
		(pad "3" smd rect
			(at -1.301 0.954)
			(size 0.7 1.2)
			(layers "F.Cu" "F.Mask" "F.Paste")
			(net 98 "/CSI/CAM_CTRL.CSIA_FLG")
			(pinfunction "FLG")
			(pintype "output")
		)
		(pad "4" smd rect
			(at 1.299 0.954)
			(size 0.7 1.2)
			(layers "F.Cu" "F.Mask" "F.Paste")
			(net 74 "/CSI/CAM_CTRL.CSIA_PEN")
			(pinfunction "EN")
			(pintype "input")
		)
		(pad "5" smd rect
			(at 1.299 0.004)
			(size 0.7 1.2)
			(layers "F.Cu" "F.Mask" "F.Paste")
			(net 995 "/CSI/CSIA_5V_ISET")
			(pinfunction "ISET")
			(pintype "passive")
		)
		(pad "6" smd rect
			(at 1.299 -0.947)
			(size 0.7 1.2)
			(layers "F.Cu" "F.Mask" "F.Paste")
			(net 5 "+5V")
			(pinfunction "IN")
			(pintype "power_in")
		)
	)
)
